FILE_TYPE = MACRO_DRAWING;
SET COLOR_WIRE YELLOW;
SET COLOR_PROP ORANGE;
SET COLOR_DOT WHITE;
SET COLOR_ARC YELLOW;
SET COLOR_BODY GREEN;
SET COLOR_NOTE PURPLE;
SET PROP_DISPLAY VALUE;
SET PAGE_NUMBER P26;
FORCEADD OFFPAGE..2
(-2475 4750);
FORCEPROP 2 LAST $XR0 53 
J 0
(-2286 4750);
DISPLAY 0.638298 (-2286 4750);
PAINT MONO (-2286 4750);
FORCEPROP 2 LAST CDS_LIB standard
J 0
(-2475 4750);
DISPLAY INVISIBLE (-2475 4750);
FORCEPROP 1 LAST OFFPAGE TRUE
J 0
(-2150 4625);
DISPLAY 0.872340 (-2150 4625);
PAINT GREEN (-2150 4625);
DISPLAY INVISIBLE (-2150 4625);
FORCEPROP 1 LAST COMMENT_BODY TRUE
J 0
(-2520 4655);
DISPLAY 0.872340 (-2520 4655);
PAINT GREEN (-2520 4655);
DISPLAY INVISIBLE (-2520 4655);
FORCEPROP 2 LAST PATH I104
J 0
(-2275 4800);
DISPLAY 1.021277 (-2275 4800);
DISPLAY INVISIBLE (-2275 4800);
FORCEADD OFFPAGE..2
(-2475 4700);
FORCEPROP 2 LAST $XR0 53 
J 0
(-2286 4700);
DISPLAY 0.638298 (-2286 4700);
PAINT MONO (-2286 4700);
FORCEPROP 2 LAST CDS_LIB standard
J 0
(-2475 4700);
DISPLAY INVISIBLE (-2475 4700);
FORCEPROP 1 LAST OFFPAGE TRUE
J 0
(-2150 4575);
DISPLAY 0.872340 (-2150 4575);
PAINT GREEN (-2150 4575);
DISPLAY INVISIBLE (-2150 4575);
FORCEPROP 1 LAST COMMENT_BODY TRUE
J 0
(-2520 4605);
DISPLAY 0.872340 (-2520 4605);
PAINT GREEN (-2520 4605);
DISPLAY INVISIBLE (-2520 4605);
FORCEPROP 2 LAST PATH I105
J 0
(-2275 4750);
DISPLAY 1.021277 (-2275 4750);
DISPLAY INVISIBLE (-2275 4750);
FORCEADD OFFPAGE..1
(-7225 5375);
FORCEPROP 2 LAST $XR0 145 
J 0
(-7477 5375);
DISPLAY 0.638298 (-7477 5375);
PAINT MONO (-7477 5375);
FORCEPROP 2 LAST CDS_LIB standard
J 0
(-7225 5375);
DISPLAY INVISIBLE (-7225 5375);
FORCEPROP 1 LAST OFFPAGE TRUE
J 0
(-6900 5250);
DISPLAY 0.872340 (-6900 5250);
PAINT GREEN (-6900 5250);
DISPLAY INVISIBLE (-6900 5250);
FORCEPROP 1 LAST COMMENT_BODY TRUE
J 0
(-7100 5275);
DISPLAY 0.872340 (-7100 5275);
PAINT GREEN (-7100 5275);
DISPLAY INVISIBLE (-7100 5275);
FORCEPROP 2 LAST PATH I117
J 0
(-7175 5450);
DISPLAY 0.680851 (-7175 5450);
DISPLAY INVISIBLE (-7175 5450);
FORCEADD OFFPAGE..1
(-7225 5425);
FORCEPROP 2 LAST $XR0 145 
J 0
(-7477 5425);
DISPLAY 0.638298 (-7477 5425);
PAINT MONO (-7477 5425);
FORCEPROP 2 LAST CDS_LIB standard
J 0
(-7225 5425);
DISPLAY INVISIBLE (-7225 5425);
FORCEPROP 1 LAST OFFPAGE TRUE
J 0
(-6900 5300);
DISPLAY 0.872340 (-6900 5300);
PAINT GREEN (-6900 5300);
DISPLAY INVISIBLE (-6900 5300);
FORCEPROP 1 LAST COMMENT_BODY TRUE
J 0
(-7100 5325);
DISPLAY 0.872340 (-7100 5325);
PAINT GREEN (-7100 5325);
DISPLAY INVISIBLE (-7100 5325);
FORCEPROP 2 LAST PATH I118
J 0
(-7175 5500);
DISPLAY 0.680851 (-7175 5500);
DISPLAY INVISIBLE (-7175 5500);
FORCEADD TAP..6
(-6200 4850);
FORCEPROP 3 LASTPIN (-6150 4850) SIG_NAME P3E_CPU0_P4_RX_DN<3>
J 0
(-6140 4860);
DISPLAY 0.659574 (-6140 4860);
PAINT MONO (-6140 4860);
DISPLAY INVISIBLE (-6140 4860);
FORCEPROP 1 LASTPIN (-6150 4850) BN 3
J 0
(-6202 4858);
DISPLAY 0.680851 (-6202 4858);
PAINT MONO (-6202 4858);
FORCEPROP 2 LAST CDS_LIB standard
J 0
(-6200 4850);
DISPLAY INVISIBLE (-6200 4850);
FORCEPROP 1 LAST BODY_TYPE PLUMBING
J 0
(-6200 4800);
DISPLAY 0.574468 (-6200 4800);
PAINT GREEN (-6200 4800);
DISPLAY INVISIBLE (-6200 4800);
FORCEPROP 1 LAST HDL_TAP TRUE
J 0
(-5875 4725);
DISPLAY 0.574468 (-5875 4725);
PAINT GREEN (-5875 4725);
DISPLAY INVISIBLE (-5875 4725);
FORCEPROP 1 LAST PATH I131
J 0
(-6202 4850);
DISPLAY 0.872340 (-6202 4850);
PAINT GREEN (-6202 4850);
DISPLAY INVISIBLE (-6202 4850);
FORCEADD TAP..6
(-6200 4950);
FORCEPROP 3 LASTPIN (-6150 4950) SIG_NAME P3E_CPU0_P4_RX_DN<2>
J 0
(-6140 4960);
DISPLAY 0.659574 (-6140 4960);
PAINT MONO (-6140 4960);
DISPLAY INVISIBLE (-6140 4960);
FORCEPROP 1 LASTPIN (-6150 4950) BN 2
J 0
(-6202 4958);
DISPLAY 0.680851 (-6202 4958);
PAINT MONO (-6202 4958);
FORCEPROP 2 LAST CDS_LIB standard
J 0
(-6200 4950);
DISPLAY INVISIBLE (-6200 4950);
FORCEPROP 1 LAST BODY_TYPE PLUMBING
J 0
(-6200 4900);
DISPLAY 0.574468 (-6200 4900);
PAINT GREEN (-6200 4900);
DISPLAY INVISIBLE (-6200 4900);
FORCEPROP 1 LAST HDL_TAP TRUE
J 0
(-5875 4825);
DISPLAY 0.574468 (-5875 4825);
PAINT GREEN (-5875 4825);
DISPLAY INVISIBLE (-5875 4825);
FORCEPROP 1 LAST PATH I132
J 0
(-6202 4950);
DISPLAY 0.872340 (-6202 4950);
PAINT GREEN (-6202 4950);
DISPLAY INVISIBLE (-6202 4950);
FORCEADD TAP..6
(-6200 5050);
FORCEPROP 3 LASTPIN (-6150 5050) SIG_NAME P3E_CPU0_P4_RX_DN<1>
J 0
(-6140 5060);
DISPLAY 0.659574 (-6140 5060);
PAINT MONO (-6140 5060);
DISPLAY INVISIBLE (-6140 5060);
FORCEPROP 1 LASTPIN (-6150 5050) BN 1
J 0
(-6202 5058);
DISPLAY 0.680851 (-6202 5058);
PAINT MONO (-6202 5058);
FORCEPROP 2 LAST CDS_LIB standard
J 0
(-6200 5050);
DISPLAY INVISIBLE (-6200 5050);
FORCEPROP 1 LAST BODY_TYPE PLUMBING
J 0
(-6200 5000);
DISPLAY 0.574468 (-6200 5000);
PAINT GREEN (-6200 5000);
DISPLAY INVISIBLE (-6200 5000);
FORCEPROP 1 LAST HDL_TAP TRUE
J 0
(-5875 4925);
DISPLAY 0.574468 (-5875 4925);
PAINT GREEN (-5875 4925);
DISPLAY INVISIBLE (-5875 4925);
FORCEPROP 1 LAST PATH I133
J 0
(-6202 5050);
DISPLAY 0.872340 (-6202 5050);
PAINT GREEN (-6202 5050);
DISPLAY INVISIBLE (-6202 5050);
FORCEADD TAP..6
(-6200 5150);
FORCEPROP 3 LASTPIN (-6150 5150) SIG_NAME P3E_CPU0_P4_RX_DN<0>
J 0
(-6140 5160);
DISPLAY 0.659574 (-6140 5160);
PAINT MONO (-6140 5160);
DISPLAY INVISIBLE (-6140 5160);
FORCEPROP 1 LASTPIN (-6150 5150) BN 0
J 0
(-6202 5158);
DISPLAY 0.680851 (-6202 5158);
PAINT MONO (-6202 5158);
FORCEPROP 2 LAST CDS_LIB standard
J 0
(-6200 5150);
DISPLAY INVISIBLE (-6200 5150);
FORCEPROP 1 LAST BODY_TYPE PLUMBING
J 0
(-6200 5100);
DISPLAY 0.574468 (-6200 5100);
PAINT GREEN (-6200 5100);
DISPLAY INVISIBLE (-6200 5100);
FORCEPROP 1 LAST HDL_TAP TRUE
J 0
(-5875 5025);
DISPLAY 0.574468 (-5875 5025);
PAINT GREEN (-5875 5025);
DISPLAY INVISIBLE (-5875 5025);
FORCEPROP 1 LAST PATH I134
J 0
(-6202 5150);
DISPLAY 0.872340 (-6202 5150);
PAINT GREEN (-6202 5150);
DISPLAY INVISIBLE (-6202 5150);
FORCEADD TAP..6
(-6050 4900);
FORCEPROP 3 LASTPIN (-6000 4900) SIG_NAME P3E_CPU0_P4_RX_DP<3>
J 0
(-5990 4910);
DISPLAY 0.659574 (-5990 4910);
PAINT MONO (-5990 4910);
DISPLAY INVISIBLE (-5990 4910);
FORCEPROP 1 LASTPIN (-6000 4900) BN 3
J 0
(-6052 4908);
DISPLAY 0.680851 (-6052 4908);
PAINT MONO (-6052 4908);
FORCEPROP 2 LAST CDS_LIB standard
J 0
(-6050 4900);
DISPLAY INVISIBLE (-6050 4900);
FORCEPROP 1 LAST BODY_TYPE PLUMBING
J 0
(-6050 4850);
DISPLAY 0.574468 (-6050 4850);
PAINT GREEN (-6050 4850);
DISPLAY INVISIBLE (-6050 4850);
FORCEPROP 1 LAST HDL_TAP TRUE
J 0
(-5725 4775);
DISPLAY 0.574468 (-5725 4775);
PAINT GREEN (-5725 4775);
DISPLAY INVISIBLE (-5725 4775);
FORCEPROP 1 LAST PATH I136
J 0
(-6052 4900);
DISPLAY 0.872340 (-6052 4900);
PAINT GREEN (-6052 4900);
DISPLAY INVISIBLE (-6052 4900);
FORCEADD TAP..6
(-6050 5000);
FORCEPROP 3 LASTPIN (-6000 5000) SIG_NAME P3E_CPU0_P4_RX_DP<2>
J 0
(-5990 5010);
DISPLAY 0.659574 (-5990 5010);
PAINT MONO (-5990 5010);
DISPLAY INVISIBLE (-5990 5010);
FORCEPROP 1 LASTPIN (-6000 5000) BN 2
J 0
(-6052 5008);
DISPLAY 0.680851 (-6052 5008);
PAINT MONO (-6052 5008);
FORCEPROP 2 LAST CDS_LIB standard
J 0
(-6050 5000);
DISPLAY INVISIBLE (-6050 5000);
FORCEPROP 1 LAST BODY_TYPE PLUMBING
J 0
(-6050 4950);
DISPLAY 0.574468 (-6050 4950);
PAINT GREEN (-6050 4950);
DISPLAY INVISIBLE (-6050 4950);
FORCEPROP 1 LAST HDL_TAP TRUE
J 0
(-5725 4875);
DISPLAY 0.574468 (-5725 4875);
PAINT GREEN (-5725 4875);
DISPLAY INVISIBLE (-5725 4875);
FORCEPROP 1 LAST PATH I137
J 0
(-6052 5000);
DISPLAY 0.872340 (-6052 5000);
PAINT GREEN (-6052 5000);
DISPLAY INVISIBLE (-6052 5000);
FORCEADD TAP..6
(-6050 5200);
FORCEPROP 3 LASTPIN (-6000 5200) SIG_NAME P3E_CPU0_P4_RX_DP<0>
J 0
(-5990 5210);
DISPLAY 0.659574 (-5990 5210);
PAINT MONO (-5990 5210);
DISPLAY INVISIBLE (-5990 5210);
FORCEPROP 1 LASTPIN (-6000 5200) BN 0
J 0
(-6052 5208);
DISPLAY 0.680851 (-6052 5208);
PAINT MONO (-6052 5208);
FORCEPROP 2 LAST CDS_LIB standard
J 0
(-6050 5200);
DISPLAY INVISIBLE (-6050 5200);
FORCEPROP 1 LAST BODY_TYPE PLUMBING
J 0
(-6050 5150);
DISPLAY 0.574468 (-6050 5150);
PAINT GREEN (-6050 5150);
DISPLAY INVISIBLE (-6050 5150);
FORCEPROP 1 LAST HDL_TAP TRUE
J 0
(-5725 5075);
DISPLAY 0.574468 (-5725 5075);
PAINT GREEN (-5725 5075);
DISPLAY INVISIBLE (-5725 5075);
FORCEPROP 1 LAST PATH I138
J 0
(-6052 5200);
DISPLAY 0.872340 (-6052 5200);
PAINT GREEN (-6052 5200);
DISPLAY INVISIBLE (-6052 5200);
FORCEADD TAP..6
(-6050 5100);
FORCEPROP 3 LASTPIN (-6000 5100) SIG_NAME P3E_CPU0_P4_RX_DP<1>
J 0
(-5990 5110);
DISPLAY 0.659574 (-5990 5110);
PAINT MONO (-5990 5110);
DISPLAY INVISIBLE (-5990 5110);
FORCEPROP 1 LASTPIN (-6000 5100) BN 1
J 0
(-6052 5108);
DISPLAY 0.680851 (-6052 5108);
PAINT MONO (-6052 5108);
FORCEPROP 2 LAST CDS_LIB standard
J 0
(-6050 5100);
DISPLAY INVISIBLE (-6050 5100);
FORCEPROP 1 LAST BODY_TYPE PLUMBING
J 0
(-6050 5050);
DISPLAY 0.574468 (-6050 5050);
PAINT GREEN (-6050 5050);
DISPLAY INVISIBLE (-6050 5050);
FORCEPROP 1 LAST HDL_TAP TRUE
J 0
(-5725 4975);
DISPLAY 0.574468 (-5725 4975);
PAINT GREEN (-5725 4975);
DISPLAY INVISIBLE (-5725 4975);
FORCEPROP 1 LAST PATH I139
J 0
(-6052 5100);
DISPLAY 0.872340 (-6052 5100);
PAINT GREEN (-6052 5100);
DISPLAY INVISIBLE (-6052 5100);
FORCEADD TAP..6
R 2
(-3200 4900);
FORCEPROP 3 LASTPIN (-3250 4900) SIG_NAME P3E_CPU0_P4_TX_DP<3>
J 0
(-3240 4910);
DISPLAY 0.659574 (-3240 4910);
PAINT MONO (-3240 4910);
DISPLAY INVISIBLE (-3240 4910);
FORCEPROP 1 LASTPIN (-3250 4900) BN 3
J 2
(-3198 4908);
DISPLAY 0.680851 (-3198 4908);
PAINT MONO (-3198 4908);
FORCEPROP 2 LAST CDS_LIB standard
J 0
(-3200 4900);
DISPLAY INVISIBLE (-3200 4900);
FORCEPROP 2 LAST BOM_COST IO_SLOT
J 0
(-3700 5000);
DISPLAY 0.829787 (-3700 5000);
DISPLAY INVISIBLE (-3700 5000);
FORCEPROP 2 LAST ROOM RISER1
J 0
(-3700 4950);
DISPLAY 0.829787 (-3700 4950);
PAINT RED (-3700 4950);
DISPLAY INVISIBLE (-3700 4950);
FORCEPROP 1 LAST BODY_TYPE PLUMBING
J 2
(-3200 4850);
DISPLAY 0.702128 (-3200 4850);
PAINT GREEN (-3200 4850);
DISPLAY INVISIBLE (-3200 4850);
FORCEPROP 1 LAST HDL_TAP TRUE
J 2
(-3525 4775);
DISPLAY 0.702128 (-3525 4775);
PAINT GREEN (-3525 4775);
DISPLAY INVISIBLE (-3525 4775);
FORCEPROP 1 LAST PATH I141
J 2
(-3198 4900);
DISPLAY 0.872340 (-3198 4900);
PAINT GREEN (-3198 4900);
DISPLAY INVISIBLE (-3198 4900);
FORCEADD TAP..6
R 2
(-3200 5000);
FORCEPROP 3 LASTPIN (-3250 5000) SIG_NAME P3E_CPU0_P4_TX_DP<2>
J 0
(-3240 5010);
DISPLAY 0.659574 (-3240 5010);
PAINT MONO (-3240 5010);
DISPLAY INVISIBLE (-3240 5010);
FORCEPROP 1 LASTPIN (-3250 5000) BN 2
J 2
(-3198 5008);
DISPLAY 0.680851 (-3198 5008);
PAINT MONO (-3198 5008);
FORCEPROP 2 LAST CDS_LIB standard
J 0
(-3200 5000);
DISPLAY INVISIBLE (-3200 5000);
FORCEPROP 2 LAST BOM_COST IO_SLOT
J 0
(-3700 5100);
DISPLAY 0.829787 (-3700 5100);
DISPLAY INVISIBLE (-3700 5100);
FORCEPROP 2 LAST ROOM RISER1
J 0
(-3700 5050);
DISPLAY 0.829787 (-3700 5050);
PAINT RED (-3700 5050);
DISPLAY INVISIBLE (-3700 5050);
FORCEPROP 1 LAST BODY_TYPE PLUMBING
J 2
(-3200 4950);
DISPLAY 0.702128 (-3200 4950);
PAINT GREEN (-3200 4950);
DISPLAY INVISIBLE (-3200 4950);
FORCEPROP 1 LAST HDL_TAP TRUE
J 2
(-3525 4875);
DISPLAY 0.702128 (-3525 4875);
PAINT GREEN (-3525 4875);
DISPLAY INVISIBLE (-3525 4875);
FORCEPROP 1 LAST PATH I142
J 2
(-3198 5000);
DISPLAY 0.872340 (-3198 5000);
PAINT GREEN (-3198 5000);
DISPLAY INVISIBLE (-3198 5000);
FORCEADD TAP..6
R 2
(-3200 5100);
FORCEPROP 3 LASTPIN (-3250 5100) SIG_NAME P3E_CPU0_P4_TX_DP<1>
J 0
(-3240 5110);
DISPLAY 0.659574 (-3240 5110);
PAINT MONO (-3240 5110);
DISPLAY INVISIBLE (-3240 5110);
FORCEPROP 1 LASTPIN (-3250 5100) BN 1
J 2
(-3198 5108);
DISPLAY 0.680851 (-3198 5108);
PAINT MONO (-3198 5108);
FORCEPROP 2 LAST CDS_LIB standard
J 0
(-3200 5100);
DISPLAY INVISIBLE (-3200 5100);
FORCEPROP 2 LAST BOM_COST IO_SLOT
J 0
(-3700 5200);
DISPLAY 0.829787 (-3700 5200);
DISPLAY INVISIBLE (-3700 5200);
FORCEPROP 2 LAST ROOM RISER1
J 0
(-3700 5150);
DISPLAY 0.829787 (-3700 5150);
PAINT RED (-3700 5150);
DISPLAY INVISIBLE (-3700 5150);
FORCEPROP 1 LAST BODY_TYPE PLUMBING
J 2
(-3200 5050);
DISPLAY 0.702128 (-3200 5050);
PAINT GREEN (-3200 5050);
DISPLAY INVISIBLE (-3200 5050);
FORCEPROP 1 LAST HDL_TAP TRUE
J 2
(-3525 4975);
DISPLAY 0.702128 (-3525 4975);
PAINT GREEN (-3525 4975);
DISPLAY INVISIBLE (-3525 4975);
FORCEPROP 1 LAST PATH I143
J 2
(-3198 5100);
DISPLAY 0.872340 (-3198 5100);
PAINT GREEN (-3198 5100);
DISPLAY INVISIBLE (-3198 5100);
FORCEADD TAP..6
R 2
(-3200 5200);
FORCEPROP 3 LASTPIN (-3250 5200) SIG_NAME P3E_CPU0_P4_TX_DP<0>
J 0
(-3240 5210);
DISPLAY 0.659574 (-3240 5210);
PAINT MONO (-3240 5210);
DISPLAY INVISIBLE (-3240 5210);
FORCEPROP 1 LASTPIN (-3250 5200) BN 0
J 2
(-3198 5208);
DISPLAY 0.680851 (-3198 5208);
PAINT MONO (-3198 5208);
FORCEPROP 2 LAST CDS_LIB standard
J 0
(-3200 5200);
DISPLAY INVISIBLE (-3200 5200);
FORCEPROP 2 LAST BOM_COST IO_SLOT
J 0
(-3700 5300);
DISPLAY 0.829787 (-3700 5300);
DISPLAY INVISIBLE (-3700 5300);
FORCEPROP 2 LAST ROOM RISER1
J 0
(-3700 5250);
DISPLAY 0.829787 (-3700 5250);
PAINT RED (-3700 5250);
DISPLAY INVISIBLE (-3700 5250);
FORCEPROP 1 LAST BODY_TYPE PLUMBING
J 2
(-3200 5150);
DISPLAY 0.702128 (-3200 5150);
PAINT GREEN (-3200 5150);
DISPLAY INVISIBLE (-3200 5150);
FORCEPROP 1 LAST HDL_TAP TRUE
J 2
(-3525 5075);
DISPLAY 0.702128 (-3525 5075);
PAINT GREEN (-3525 5075);
DISPLAY INVISIBLE (-3525 5075);
FORCEPROP 1 LAST PATH I144
J 2
(-3198 5200);
DISPLAY 0.872340 (-3198 5200);
PAINT GREEN (-3198 5200);
DISPLAY INVISIBLE (-3198 5200);
FORCEADD TAP..6
R 2
(-3050 4850);
FORCEPROP 3 LASTPIN (-3100 4850) SIG_NAME P3E_CPU0_P4_TX_DN<3>
J 0
(-3090 4860);
DISPLAY 0.659574 (-3090 4860);
PAINT MONO (-3090 4860);
DISPLAY INVISIBLE (-3090 4860);
FORCEPROP 1 LASTPIN (-3100 4850) BN 3
J 2
(-3048 4858);
DISPLAY 0.680851 (-3048 4858);
PAINT MONO (-3048 4858);
FORCEPROP 2 LAST CDS_LIB standard
J 0
(-3050 4850);
DISPLAY INVISIBLE (-3050 4850);
FORCEPROP 2 LAST BOM_COST IO_SLOT
J 0
(-3550 4950);
DISPLAY 0.829787 (-3550 4950);
DISPLAY INVISIBLE (-3550 4950);
FORCEPROP 2 LAST ROOM RISER1
J 0
(-3550 4900);
DISPLAY 0.829787 (-3550 4900);
PAINT RED (-3550 4900);
DISPLAY INVISIBLE (-3550 4900);
FORCEPROP 1 LAST BODY_TYPE PLUMBING
J 2
(-3050 4800);
DISPLAY 0.702128 (-3050 4800);
PAINT GREEN (-3050 4800);
DISPLAY INVISIBLE (-3050 4800);
FORCEPROP 1 LAST HDL_TAP TRUE
J 2
(-3375 4725);
DISPLAY 0.702128 (-3375 4725);
PAINT GREEN (-3375 4725);
DISPLAY INVISIBLE (-3375 4725);
FORCEPROP 1 LAST PATH I146
J 2
(-3048 4850);
DISPLAY 0.872340 (-3048 4850);
PAINT GREEN (-3048 4850);
DISPLAY INVISIBLE (-3048 4850);
FORCEADD TAP..6
R 2
(-3050 4950);
FORCEPROP 3 LASTPIN (-3100 4950) SIG_NAME P3E_CPU0_P4_TX_DN<2>
J 0
(-3090 4960);
DISPLAY 0.659574 (-3090 4960);
PAINT MONO (-3090 4960);
DISPLAY INVISIBLE (-3090 4960);
FORCEPROP 1 LASTPIN (-3100 4950) BN 2
J 2
(-3048 4958);
DISPLAY 0.680851 (-3048 4958);
PAINT MONO (-3048 4958);
FORCEPROP 2 LAST CDS_LIB standard
J 0
(-3050 4950);
DISPLAY INVISIBLE (-3050 4950);
FORCEPROP 2 LAST BOM_COST IO_SLOT
J 0
(-3550 5050);
DISPLAY 0.829787 (-3550 5050);
DISPLAY INVISIBLE (-3550 5050);
FORCEPROP 2 LAST ROOM RISER1
J 0
(-3550 5000);
DISPLAY 0.829787 (-3550 5000);
PAINT RED (-3550 5000);
DISPLAY INVISIBLE (-3550 5000);
FORCEPROP 1 LAST BODY_TYPE PLUMBING
J 2
(-3050 4900);
DISPLAY 0.702128 (-3050 4900);
PAINT GREEN (-3050 4900);
DISPLAY INVISIBLE (-3050 4900);
FORCEPROP 1 LAST HDL_TAP TRUE
J 2
(-3375 4825);
DISPLAY 0.702128 (-3375 4825);
PAINT GREEN (-3375 4825);
DISPLAY INVISIBLE (-3375 4825);
FORCEPROP 1 LAST PATH I147
J 2
(-3048 4950);
DISPLAY 0.872340 (-3048 4950);
PAINT GREEN (-3048 4950);
DISPLAY INVISIBLE (-3048 4950);
FORCEADD TAP..6
R 2
(-3050 5150);
FORCEPROP 3 LASTPIN (-3100 5150) SIG_NAME P3E_CPU0_P4_TX_DN<0>
J 0
(-3090 5160);
DISPLAY 0.659574 (-3090 5160);
PAINT MONO (-3090 5160);
DISPLAY INVISIBLE (-3090 5160);
FORCEPROP 1 LASTPIN (-3100 5150) BN 0
J 2
(-3048 5158);
DISPLAY 0.680851 (-3048 5158);
PAINT MONO (-3048 5158);
FORCEPROP 2 LAST CDS_LIB standard
J 0
(-3050 5150);
DISPLAY INVISIBLE (-3050 5150);
FORCEPROP 2 LAST BOM_COST IO_SLOT
J 0
(-3550 5250);
DISPLAY 0.829787 (-3550 5250);
DISPLAY INVISIBLE (-3550 5250);
FORCEPROP 2 LAST ROOM RISER1
J 0
(-3550 5200);
DISPLAY 0.829787 (-3550 5200);
PAINT RED (-3550 5200);
DISPLAY INVISIBLE (-3550 5200);
FORCEPROP 1 LAST BODY_TYPE PLUMBING
J 2
(-3050 5100);
DISPLAY 0.702128 (-3050 5100);
PAINT GREEN (-3050 5100);
DISPLAY INVISIBLE (-3050 5100);
FORCEPROP 1 LAST HDL_TAP TRUE
J 2
(-3375 5025);
DISPLAY 0.702128 (-3375 5025);
PAINT GREEN (-3375 5025);
DISPLAY INVISIBLE (-3375 5025);
FORCEPROP 1 LAST PATH I148
J 2
(-3048 5150);
DISPLAY 0.872340 (-3048 5150);
PAINT GREEN (-3048 5150);
DISPLAY INVISIBLE (-3048 5150);
FORCEADD TAP..6
R 2
(-3050 5050);
FORCEPROP 3 LASTPIN (-3100 5050) SIG_NAME P3E_CPU0_P4_TX_DN<1>
J 0
(-3090 5060);
DISPLAY 0.659574 (-3090 5060);
PAINT MONO (-3090 5060);
DISPLAY INVISIBLE (-3090 5060);
FORCEPROP 1 LASTPIN (-3100 5050) BN 1
J 2
(-3048 5058);
DISPLAY 0.680851 (-3048 5058);
PAINT MONO (-3048 5058);
FORCEPROP 2 LAST CDS_LIB standard
J 0
(-3050 5050);
DISPLAY INVISIBLE (-3050 5050);
FORCEPROP 2 LAST BOM_COST IO_SLOT
J 0
(-3550 5150);
DISPLAY 0.829787 (-3550 5150);
DISPLAY INVISIBLE (-3550 5150);
FORCEPROP 2 LAST ROOM RISER1
J 0
(-3550 5100);
DISPLAY 0.829787 (-3550 5100);
PAINT RED (-3550 5100);
DISPLAY INVISIBLE (-3550 5100);
FORCEPROP 1 LAST BODY_TYPE PLUMBING
J 2
(-3050 5000);
DISPLAY 0.702128 (-3050 5000);
PAINT GREEN (-3050 5000);
DISPLAY INVISIBLE (-3050 5000);
FORCEPROP 1 LAST HDL_TAP TRUE
J 2
(-3375 4925);
DISPLAY 0.702128 (-3375 4925);
PAINT GREEN (-3375 4925);
DISPLAY INVISIBLE (-3375 4925);
FORCEPROP 1 LAST PATH I149
J 2
(-3048 5050);
DISPLAY 0.872340 (-3048 5050);
PAINT GREEN (-3048 5050);
DISPLAY INVISIBLE (-3048 5050);
FORCEADD OFFPAGE..2
(-2100 5375);
FORCEPROP 2 LAST $XR0 67 
J 0
(-1911 5375);
DISPLAY 0.638298 (-1911 5375);
PAINT MONO (-1911 5375);
FORCEPROP 2 LAST CDS_LIB standard
J 0
(-2100 5375);
DISPLAY INVISIBLE (-2100 5375);
FORCEPROP 1 LAST OFFPAGE TRUE
J 0
(-1775 5250);
DISPLAY 0.872340 (-1775 5250);
PAINT GREEN (-1775 5250);
DISPLAY INVISIBLE (-1775 5250);
FORCEPROP 1 LAST COMMENT_BODY TRUE
J 0
(-2145 5280);
DISPLAY 0.872340 (-2145 5280);
PAINT GREEN (-2145 5280);
DISPLAY INVISIBLE (-2145 5280);
FORCEPROP 2 LAST PATH I150
J 0
(-1925 5450);
DISPLAY 0.680851 (-1925 5450);
DISPLAY INVISIBLE (-1925 5450);
FORCEADD OFFPAGE..2
(-2100 5425);
FORCEPROP 2 LAST $XR0 67 
J 0
(-1911 5425);
DISPLAY 0.638298 (-1911 5425);
PAINT MONO (-1911 5425);
FORCEPROP 2 LAST CDS_LIB standard
J 0
(-2100 5425);
DISPLAY INVISIBLE (-2100 5425);
FORCEPROP 1 LAST OFFPAGE TRUE
J 0
(-1775 5300);
DISPLAY 0.872340 (-1775 5300);
PAINT GREEN (-1775 5300);
DISPLAY INVISIBLE (-1775 5300);
FORCEPROP 1 LAST COMMENT_BODY TRUE
J 0
(-2145 5330);
DISPLAY 0.872340 (-2145 5330);
PAINT GREEN (-2145 5330);
DISPLAY INVISIBLE (-2145 5330);
FORCEPROP 2 LAST PATH I151
J 0
(-1925 5500);
DISPLAY 0.680851 (-1925 5500);
DISPLAY INVISIBLE (-1925 5500);
FORCEADD OFFPAGE..4
R 2
(-6675 4450);
FORCEPROP 2 LAST $XR0 150 
J 0
(-6957 4450);
DISPLAY 0.638298 (-6957 4450);
PAINT MONO (-6957 4450);
FORCEPROP 2 LAST CDS_LIB standard
J 0
(-6675 4450);
DISPLAY INVISIBLE (-6675 4450);
FORCEPROP 1 LAST OFFPAGE TRUE
J 2
(-7000 4325);
DISPLAY 0.872340 (-7000 4325);
PAINT GREEN (-7000 4325);
DISPLAY INVISIBLE (-7000 4325);
FORCEPROP 1 LAST COMMENT_BODY TRUE
J 2
(-6650 4350);
DISPLAY 0.872340 (-6650 4350);
PAINT GREEN (-6650 4350);
DISPLAY INVISIBLE (-6650 4350);
FORCEPROP 2 LAST PATH I154
J 0
(-6625 4525);
DISPLAY 0.680851 (-6625 4525);
DISPLAY INVISIBLE (-6625 4525);
FORCEADD OFFPAGE..4
R 2
(-6675 4400);
FORCEPROP 2 LAST $XR0 150 
J 0
(-6957 4400);
DISPLAY 0.638298 (-6957 4400);
PAINT MONO (-6957 4400);
FORCEPROP 2 LAST CDS_LIB standard
J 0
(-6675 4400);
DISPLAY INVISIBLE (-6675 4400);
FORCEPROP 1 LAST OFFPAGE TRUE
J 2
(-7000 4275);
DISPLAY 0.872340 (-7000 4275);
PAINT GREEN (-7000 4275);
DISPLAY INVISIBLE (-7000 4275);
FORCEPROP 1 LAST COMMENT_BODY TRUE
J 2
(-6650 4300);
DISPLAY 0.872340 (-6650 4300);
PAINT GREEN (-6650 4300);
DISPLAY INVISIBLE (-6650 4300);
FORCEPROP 2 LAST PATH I155
J 0
(-6625 4475);
DISPLAY 0.680851 (-6625 4475);
DISPLAY INVISIBLE (-6625 4475);
FORCEADD Q_CAP_DIFFBUS..2
(-2700 4450);
FORCEPROP 1 LAST LOCATION C2077
J 0
(-2575 4450);
DISPLAY 0.723404 (-2575 4450);
PAINT GREEN (-2575 4450);
FORCEPROP 0 LAST $SEC 1
J 0
(-2575 4500);
DISPLAY 0.680851 (-2575 4500);
PAINT MONO (-2575 4500);
DISPLAY INVISIBLE (-2575 4500);
FORCEPROP 0 LAST CDS_SEC 1
J 0
(-2575 4500);
DISPLAY 0.680851 (-2575 4500);
DISPLAY INVISIBLE (-2575 4500);
FORCEPROP 0 LASTPIN (-2775 4450) $PN 1
J 2
(-2785 4460);
DISPLAY 0.680851 (-2785 4460);
PAINT MONO (-2785 4460);
FORCEPROP 0 LASTPIN (-2625 4450) $PN 2
J 0
(-2615 4460);
DISPLAY 0.680851 (-2615 4460);
PAINT MONO (-2615 4460);
FORCEPROP 0 LAST TOLERANCE 20%
J 0
(-2775 4200);
DISPLAY 0.680851 (-2775 4200);
DISPLAY INVISIBLE (-2775 4200);
FORCEPROP 0 LAST VALUE DIFF BUS_0.22UF
J 0
(-2775 4300);
DISPLAY 0.680851 (-2775 4300);
DISPLAY INVISIBLE (-2775 4300);
FORCEPROP 0 LAST VOLTAGE 6.3V
J 0
(-2775 4150);
DISPLAY 0.680851 (-2775 4150);
DISPLAY INVISIBLE (-2775 4150);
FORCEPROP 0 LAST PACK_TYPE C0201
J 0
(-2775 4250);
DISPLAY 0.680851 (-2775 4250);
DISPLAY INVISIBLE (-2775 4250);
FORCEPROP 1 LAST MATERIAL X6S
J 0
(-2775 4100);
DISPLAY 0.723404 (-2775 4100);
PAINT GREEN (-2775 4100);
DISPLAY INVISIBLE (-2775 4100);
FORCEPROP 2 LAST CDS_LIB pure_quanta
J 0
(-2700 4450);
DISPLAY INVISIBLE (-2700 4450);
FORCEPROP 1 LAST PIN_NAMES_ROTATE True
J 0
(-2700 4450);
DISPLAY 0.489362 (-2700 4450);
PAINT GREEN (-2700 4450);
DISPLAY INVISIBLE (-2700 4450);
FORCEPROP 1 LAST CDS_LMAN_SYM_OUTLINE -25,50,25,-50
J 0
(-2700 4450);
DISPLAY 0.468085 (-2700 4450);
PAINT GREEN (-2700 4450);
DISPLAY INVISIBLE (-2700 4450);
FORCEPROP 1 LAST PATH I156
J 0
(-2700 4450);
DISPLAY 0.723404 (-2700 4450);
DISPLAY INVISIBLE (-2700 4450);
FORCEPROP 1 LAST PART_NUMBER SP_CH4221MEE01
J 0
(-2775 4350);
DISPLAY 0.723404 (-2775 4350);
PAINT GREEN (-2775 4350);
DISPLAY INVISIBLE (-2775 4350);
FORCEADD Q_CAP_DIFFBUS..2
(-2700 4400);
FORCEPROP 1 LAST LOCATION C2078
J 0
(-2575 4400);
DISPLAY 0.723404 (-2575 4400);
PAINT GREEN (-2575 4400);
FORCEPROP 0 LAST $SEC 1
J 0
(-2575 4450);
DISPLAY 0.680851 (-2575 4450);
PAINT MONO (-2575 4450);
DISPLAY INVISIBLE (-2575 4450);
FORCEPROP 0 LAST CDS_SEC 1
J 0
(-2575 4450);
DISPLAY 0.680851 (-2575 4450);
DISPLAY INVISIBLE (-2575 4450);
FORCEPROP 0 LASTPIN (-2775 4400) $PN 1
J 2
(-2785 4410);
DISPLAY 0.680851 (-2785 4410);
PAINT MONO (-2785 4410);
FORCEPROP 0 LASTPIN (-2625 4400) $PN 2
J 0
(-2615 4410);
DISPLAY 0.680851 (-2615 4410);
PAINT MONO (-2615 4410);
FORCEPROP 2 LAST TOLERANCE 20%
J 0
(-2775 4150);
DISPLAY 0.680851 (-2775 4150);
FORCEPROP 1 LAST MATERIAL X6S
J 0
(-2775 4050);
DISPLAY 0.723404 (-2775 4050);
PAINT GREEN (-2775 4050);
FORCEPROP 2 LAST VOLTAGE 6.3V
J 0
(-2775 4100);
DISPLAY 0.680851 (-2775 4100);
FORCEPROP 2 LAST PACK_TYPE C0201
J 0
(-2775 4200);
DISPLAY 0.680851 (-2775 4200);
FORCEPROP 2 LAST VALUE DIFF BUS_0.22UF
J 0
(-2775 4250);
DISPLAY 0.680851 (-2775 4250);
FORCEPROP 2 LAST CDS_LIB pure_quanta
J 0
(-2700 4400);
DISPLAY INVISIBLE (-2700 4400);
FORCEPROP 1 LAST PIN_NAMES_ROTATE True
J 0
(-2700 4400);
DISPLAY 0.489362 (-2700 4400);
PAINT GREEN (-2700 4400);
DISPLAY INVISIBLE (-2700 4400);
FORCEPROP 1 LAST CDS_LMAN_SYM_OUTLINE -25,50,25,-50
J 0
(-2700 4400);
DISPLAY 0.468085 (-2700 4400);
PAINT GREEN (-2700 4400);
DISPLAY INVISIBLE (-2700 4400);
FORCEPROP 1 LAST PATH I157
J 0
(-2700 4400);
DISPLAY 0.723404 (-2700 4400);
DISPLAY INVISIBLE (-2700 4400);
FORCEPROP 1 LAST PART_NUMBER SP_CH4221MEE01
J 0
(-2775 4300);
DISPLAY 0.723404 (-2775 4300);
PAINT GREEN (-2775 4300);
DISPLAY INVISIBLE (-2775 4300);
FORCEADD OFFPAGE..2
(-1550 4450);
FORCEPROP 2 LAST $XR0 150 
J 0
(-1361 4450);
DISPLAY 0.638298 (-1361 4450);
PAINT MONO (-1361 4450);
FORCEPROP 2 LAST CDS_LIB standard
J 0
(-1550 4450);
DISPLAY INVISIBLE (-1550 4450);
FORCEPROP 1 LAST OFFPAGE TRUE
J 0
(-1225 4325);
DISPLAY 0.872340 (-1225 4325);
PAINT GREEN (-1225 4325);
DISPLAY INVISIBLE (-1225 4325);
FORCEPROP 1 LAST COMMENT_BODY TRUE
J 0
(-1595 4355);
DISPLAY 0.872340 (-1595 4355);
PAINT GREEN (-1595 4355);
DISPLAY INVISIBLE (-1595 4355);
FORCEPROP 2 LAST PATH I158
J 0
(-1375 4525);
DISPLAY 0.680851 (-1375 4525);
DISPLAY INVISIBLE (-1375 4525);
FORCEADD OFFPAGE..2
(-1550 4400);
FORCEPROP 2 LAST $XR0 150 
J 0
(-1361 4400);
DISPLAY 0.638298 (-1361 4400);
PAINT MONO (-1361 4400);
FORCEPROP 2 LAST CDS_LIB standard
J 0
(-1550 4400);
DISPLAY INVISIBLE (-1550 4400);
FORCEPROP 1 LAST OFFPAGE TRUE
J 0
(-1225 4275);
DISPLAY 0.872340 (-1225 4275);
PAINT GREEN (-1225 4275);
DISPLAY INVISIBLE (-1225 4275);
FORCEPROP 1 LAST COMMENT_BODY TRUE
J 0
(-1595 4305);
DISPLAY 0.872340 (-1595 4305);
PAINT GREEN (-1595 4305);
DISPLAY INVISIBLE (-1595 4305);
FORCEPROP 2 LAST PATH I159
J 0
(-1375 4475);
DISPLAY 0.680851 (-1375 4475);
DISPLAY INVISIBLE (-1375 4475);
FORCEADD GENOA_SP5..19
(-4575 4800);
FORCEPROP 1 LAST LOCATION U25
J 0
(-5375 5650);
DISPLAY 0.489362 (-5375 5650);
PAINT SKYBLUE (-5375 5650);
FORCEPROP 0 LAST $SEC 19
J 0
(-5350 5675);
DISPLAY 0.680851 (-5350 5675);
PAINT MONO (-5350 5675);
DISPLAY INVISIBLE (-5350 5675);
FORCEPROP 0 LAST CDS_SEC 19
J 0
(-5375 5675);
DISPLAY 1.021277 (-5375 5675);
DISPLAY INVISIBLE (-5375 5675);
FORCEPROP 0 LASTPIN (-5525 5150) $PN DG53
J 2
(-5535 5160);
DISPLAY 0.489362 (-5535 5160);
PAINT MONO (-5535 5160);
FORCEPROP 0 LASTPIN (-5525 5050) $PN DG50
J 2
(-5535 5060);
DISPLAY 0.489362 (-5535 5060);
PAINT MONO (-5535 5060);
FORCEPROP 0 LASTPIN (-5525 4950) $PN DG47
J 2
(-5535 4960);
DISPLAY 0.489362 (-5535 4960);
PAINT MONO (-5535 4960);
FORCEPROP 0 LASTPIN (-5525 4850) $PN DG44
J 2
(-5535 4860);
DISPLAY 0.489362 (-5535 4860);
PAINT MONO (-5535 4860);
FORCEPROP 0 LASTPIN (-5525 5200) $PN DG54
J 2
(-5535 5210);
DISPLAY 0.489362 (-5535 5210);
PAINT MONO (-5535 5210);
FORCEPROP 0 LASTPIN (-5525 5100) $PN DG51
J 2
(-5535 5110);
DISPLAY 0.489362 (-5535 5110);
PAINT MONO (-5535 5110);
FORCEPROP 0 LASTPIN (-5525 5000) $PN DG48
J 2
(-5535 5010);
DISPLAY 0.489362 (-5535 5010);
PAINT MONO (-5535 5010);
FORCEPROP 0 LASTPIN (-5525 4900) $PN DG45
J 2
(-5535 4910);
DISPLAY 0.489362 (-5535 4910);
PAINT MONO (-5535 4910);
FORCEPROP 0 LASTPIN (-3625 5150) $PN DE52
J 0
(-3615 5160);
DISPLAY 0.489362 (-3615 5160);
PAINT MONO (-3615 5160);
FORCEPROP 0 LASTPIN (-3625 5050) $PN DE49
J 0
(-3615 5060);
DISPLAY 0.489362 (-3615 5060);
PAINT MONO (-3615 5060);
FORCEPROP 0 LASTPIN (-3625 4950) $PN DE46
J 0
(-3615 4960);
DISPLAY 0.489362 (-3615 4960);
PAINT MONO (-3615 4960);
FORCEPROP 0 LASTPIN (-3625 4850) $PN DE43
J 0
(-3615 4860);
DISPLAY 0.489362 (-3615 4860);
PAINT MONO (-3615 4860);
FORCEPROP 0 LASTPIN (-3625 5200) $PN DE53
J 0
(-3615 5210);
DISPLAY 0.489362 (-3615 5210);
PAINT MONO (-3615 5210);
FORCEPROP 0 LASTPIN (-3625 5100) $PN DE50
J 0
(-3615 5110);
DISPLAY 0.489362 (-3615 5110);
PAINT MONO (-3615 5110);
FORCEPROP 0 LASTPIN (-3625 5000) $PN DE47
J 0
(-3615 5010);
DISPLAY 0.489362 (-3615 5010);
PAINT MONO (-3615 5010);
FORCEPROP 0 LASTPIN (-3625 4900) $PN DE44
J 0
(-3615 4910);
DISPLAY 0.489362 (-3615 4910);
PAINT MONO (-3615 4910);
FORCEPROP 0 LASTPIN (-5525 4400) $PN E44
J 2
(-5535 4410);
DISPLAY 0.489362 (-5535 4410);
PAINT MONO (-5535 4410);
FORCEPROP 0 LASTPIN (-5525 4300) $PN E41
J 2
(-5535 4310);
DISPLAY 0.489362 (-5535 4310);
PAINT MONO (-5535 4310);
FORCEPROP 0 LASTPIN (-5525 4450) $PN E43
J 2
(-5535 4460);
DISPLAY 0.489362 (-5535 4460);
PAINT MONO (-5535 4460);
FORCEPROP 0 LASTPIN (-5525 4350) $PN E40
J 2
(-5535 4360);
DISPLAY 0.489362 (-5535 4360);
PAINT MONO (-5535 4360);
FORCEPROP 0 LASTPIN (-3625 4400) $PN C45
J 0
(-3615 4410);
DISPLAY 0.489362 (-3615 4410);
PAINT MONO (-3615 4410);
FORCEPROP 0 LASTPIN (-3625 4300) $PN C42
J 0
(-3615 4310);
DISPLAY 0.489362 (-3615 4310);
PAINT MONO (-3615 4310);
FORCEPROP 0 LASTPIN (-3625 4450) $PN C44
J 0
(-3615 4460);
DISPLAY 0.489362 (-3615 4460);
PAINT MONO (-3615 4460);
FORCEPROP 0 LASTPIN (-3625 4350) $PN C41
J 0
(-3615 4360);
DISPLAY 0.489362 (-3615 4360);
PAINT MONO (-3615 4360);
FORCEPROP 0 LASTPIN (-5525 4700) $PN E50
J 2
(-5535 4710);
DISPLAY 0.489362 (-5535 4710);
PAINT MONO (-5535 4710);
FORCEPROP 0 LASTPIN (-5525 4600) $PN E47
J 2
(-5535 4610);
DISPLAY 0.489362 (-5535 4610);
PAINT MONO (-5535 4610);
FORCEPROP 0 LASTPIN (-5525 4750) $PN E49
J 2
(-5535 4760);
DISPLAY 0.489362 (-5535 4760);
PAINT MONO (-5535 4760);
FORCEPROP 0 LASTPIN (-5525 4650) $PN E46
J 2
(-5535 4660);
DISPLAY 0.489362 (-5535 4660);
PAINT MONO (-5535 4660);
FORCEPROP 0 LASTPIN (-3625 4700) $PN C51
J 0
(-3615 4710);
DISPLAY 0.489362 (-3615 4710);
PAINT MONO (-3615 4710);
FORCEPROP 0 LASTPIN (-3625 4600) $PN C48
J 0
(-3615 4610);
DISPLAY 0.489362 (-3615 4610);
PAINT MONO (-3615 4610);
FORCEPROP 0 LASTPIN (-3625 4750) $PN C50
J 0
(-3615 4760);
DISPLAY 0.489362 (-3615 4760);
PAINT MONO (-3615 4760);
FORCEPROP 0 LASTPIN (-3625 4650) $PN C47
J 0
(-3615 4660);
DISPLAY 0.489362 (-3615 4660);
PAINT MONO (-3615 4660);
FORCEPROP 1 LAST MATERIAL IO
J 0
(-5370 5432);
DISPLAY 0.489362 (-5370 5432);
PAINT SKYBLUE (-5370 5432);
FORCEPROP 2 LAST VALUE SOCKET6096_13568-001
J 0
(-5375 5475);
DISPLAY 0.489362 (-5375 5475);
PAINT SKYBLUE (-5375 5475);
FORCEPROP 2 LAST PART_TYPE SMLF
J 0
(-5375 5575);
DISPLAY 1.021277 (-5375 5575);
FORCEPROP 1 LAST CDS_LMAN_SYM_OUTLINE -800,600,800,-600
J 0
(-4575 4800);
DISPLAY 0.468085 (-4575 4800);
PAINT GREEN (-4575 4800);
DISPLAY INVISIBLE (-4575 4800);
FORCEPROP 1 LAST NEEDS_NO_SIZE TRUE
J 0
(-4575 4800);
DISPLAY 0.723404 (-4575 4800);
PAINT GREEN (-4575 4800);
DISPLAY INVISIBLE (-4575 4800);
FORCEPROP 2 LAST CDS_LIB pure_quanta
J 0
(-4575 4800);
DISPLAY INVISIBLE (-4575 4800);
FORCEPROP 1 LAST PATH I59
J 0
(-4575 4800);
DISPLAY 0.723404 (-4575 4800);
PAINT GREEN (-4575 4800);
DISPLAY INVISIBLE (-4575 4800);
FORCEPROP 1 LAST PART_NUMBER DGA^6000030
J 0
(-5375 5525);
DISPLAY 0.489362 (-5375 5525);
PAINT SKYBLUE (-5375 5525);
DISPLAY INVISIBLE (-5375 5525);
FORCEADD OFFPAGE..4
R 2
(-6675 4750);
FORCEPROP 2 LAST $XR0 53 
J 0
(-6926 4750);
DISPLAY 0.638298 (-6926 4750);
PAINT MONO (-6926 4750);
FORCEPROP 2 LAST CDS_LIB standard
J 0
(-6675 4750);
DISPLAY INVISIBLE (-6675 4750);
FORCEPROP 1 LAST OFFPAGE TRUE
J 2
(-7000 4625);
DISPLAY 0.872340 (-7000 4625);
PAINT GREEN (-7000 4625);
DISPLAY INVISIBLE (-7000 4625);
FORCEPROP 1 LAST COMMENT_BODY TRUE
J 2
(-6650 4650);
DISPLAY 0.872340 (-6650 4650);
PAINT GREEN (-6650 4650);
DISPLAY INVISIBLE (-6650 4650);
FORCEPROP 2 LAST PATH I86
J 0
(-6925 4800);
DISPLAY 1.021277 (-6925 4800);
DISPLAY INVISIBLE (-6925 4800);
FORCEADD OFFPAGE..4
R 2
(-6675 4700);
FORCEPROP 2 LAST $XR0 53 
J 0
(-6926 4700);
DISPLAY 0.638298 (-6926 4700);
PAINT MONO (-6926 4700);
FORCEPROP 2 LAST CDS_LIB standard
J 0
(-6675 4700);
DISPLAY INVISIBLE (-6675 4700);
FORCEPROP 1 LAST OFFPAGE TRUE
J 2
(-7000 4575);
DISPLAY 0.872340 (-7000 4575);
PAINT GREEN (-7000 4575);
DISPLAY INVISIBLE (-7000 4575);
FORCEPROP 1 LAST COMMENT_BODY TRUE
J 2
(-6650 4600);
DISPLAY 0.872340 (-6650 4600);
PAINT GREEN (-6650 4600);
DISPLAY INVISIBLE (-6650 4600);
FORCEPROP 2 LAST PATH I87
J 0
(-6925 4750);
DISPLAY 1.021277 (-6925 4750);
DISPLAY INVISIBLE (-6925 4750);
FORCEADD QUANTA_TITLE_BLOCK_C..1
(0 0);
FORCEPROP 0 LAST CDS_CON_LAST_MODIFIED Thu Sep 14 16:11:52 2023
J 0
(-1885 15);
DISPLAY INVISIBLE (-1885 15);
FORCEPROP 1 LAST CUSTOM_TXT_CDS <CON_LAST_MODIFIED>
J 0
(-1885 15);
DISPLAY 0.978723 (-1885 15);
FORCEPROP 2 LAST CUSTOM_TXT_CDS <XR_PAGE_TITLE>
J 0
(-7890 5250);
DISPLAY 0.638298 (-7890 5250);
PAINT PINK (-7890 5250);
DISPLAY INVISIBLE (-7890 5250);
FORCEPROP 1 LAST CUSTOM_TXT_CDS <NAME_2>
J 0
(-3175 50);
FORCEPROP 1 LAST CUSTOM_TXT_CDS <NAME_1>
J 0
(-3175 175);
FORCEPROP 1 LAST CUSTOM_TXT_CDS <Q_NUMBER>
J 0
(-1403 103);
DISPLAY 1.212766 (-1403 103);
FORCEPROP 1 LAST CUSTOM_TXT_CDS <Q_PROJ>
J 0
(-2382 102);
DISPLAY 1.212766 (-2382 102);
FORCEPROP 1 LAST CUSTOM_TXT_CDS <Q_REV>
J 0
(-184 103);
DISPLAY 1.212766 (-184 103);
FORCEPROP 1 LAST CUSTOM_TXT_CDS <CON_PAGE_NUM> OF <CON_TOTAL_PAGES>
J 0
(-446 18);
DISPLAY 0.978723 (-446 18);
FORCEPROP 1 LAST Q_TITLE CPU0 PCIE P4/P5/WAFL
J 0
(-9366 26);
DISPLAY 2.446809 (-9366 26);
PAINT GREEN (-9366 26);
FORCEPROP 2 LAST PAGE_BORDER TRUE
J 0
(-7890 5250);
DISPLAY 0.638298 (-7890 5250);
PAINT PINK (-7890 5250);
DISPLAY INVISIBLE (-7890 5250);
FORCEPROP 2 LAST CDS_LIB pure_quanta
J 0
(0 0);
DISPLAY INVISIBLE (0 0);
FORCEPROP 1 LAST CDS_LMAN_SYM_OUTLINE -9475,6775,100,-125
J 0
(0 0);
DISPLAY 0.468085 (0 0);
PAINT GREEN (0 0);
DISPLAY INVISIBLE (0 0);
FORCEPROP 2 LAST CDS_XR_PAGE_TITLE CR-26 : @T6G_MB_LIB.T6G(SCH_1):PAGE26
J 0
(-7890 5250);
DISPLAY 0.638298 (-7890 5250);
PAINT PINK (-7890 5250);
DISPLAY INVISIBLE (-7890 5250);
FORCEPROP 1 LAST Q_DEPT BU9
J 1
(-3763 49);
DISPLAY 1.957447 (-3763 49);
PAINT GREEN (-3763 49);
DISPLAY INVISIBLE (-3763 49);
FORCEPROP 1 LAST COMMENT_BODY TRUE
J 0
(12 -13);
DISPLAY 0.978723 (12 -13);
PAINT GREEN (12 -13);
DISPLAY INVISIBLE (12 -13);
WIRE 17 -1 (-6100 5025)(-6100 5125);
WIRE 17 -1 (-6100 4925)(-6100 5025);
WIRE 17 -1 (-6100 5125)(-6100 5225);
WIRE 17 -1 (-6100 5225)(-6100 5425);
WIRE 17 -1 (-6100 5425)(-7175 5425);
FORCEPROP 2 LAST SIG_NAME P3E_CPU0_P4_RX_DP<3:0>
J 0
(-6985 5435);
DISPLAY 0.489362 (-6985 5435);
WIRE 17 -1 (-6250 5075)(-6250 5175);
WIRE 17 -1 (-6250 4975)(-6250 5075);
WIRE 17 -1 (-6250 5175)(-6250 5375);
WIRE 17 -1 (-6250 5375)(-7175 5375);
FORCEPROP 2 LAST SIG_NAME P3E_CPU0_P4_RX_DN<3:0>
J 0
(-6985 5385);
DISPLAY 0.489362 (-6985 5385);
WIRE 17 -1 (-3000 5175)(-3000 5075);
WIRE 17 -1 (-3000 5375)(-3000 5175);
WIRE 17 -1 (-3000 5075)(-3000 4975);
WIRE 17 -1 (-3000 4975)(-3000 4875);
WIRE 17 -1 (-3000 5375)(-2150 5375);
FORCEPROP 2 LAST SIG_NAME P3E_CPU0_P4_TX_DN<3:0>
J 0
(-2910 5385);
DISPLAY 0.489362 (-2910 5385);
WIRE 17 -1 (-3150 5225)(-3150 5125);
WIRE 17 -1 (-3150 5425)(-3150 5225);
WIRE 17 -1 (-3150 5125)(-3150 5025);
WIRE 17 -1 (-3150 5025)(-3150 4925);
WIRE 17 -1 (-3150 5425)(-2150 5425);
FORCEPROP 2 LAST SIG_NAME P3E_CPU0_P4_TX_DP<3:0>
J 0
(-2885 5435);
DISPLAY 0.489362 (-2885 5435);
WIRE 17 -1 (-6250 4875)(-6250 4975);
WIRE 16 -1 (-2625 4400)(-1600 4400);
FORCEPROP 2 LAST SIG_NAME P2E_CPU0_P5_TX_C_DN
J 0
(-2385 4410);
DISPLAY 0.680851 (-2385 4410);
WIRE 16 -1 (-2625 4450)(-1600 4450);
FORCEPROP 2 LAST SIG_NAME P2E_CPU0_P5_TX_C_DP
J 0
(-2385 4460);
DISPLAY 0.680851 (-2385 4460);
WIRE 16 -1 (-3625 4850)(-3100 4850);
WIRE 16 -1 (-3625 4750)(-2525 4750);
FORCEPROP 2 LAST SIG_NAME WAFL_CPU0_TX0_CPU1_RX1_DP
J 0
(-3360 4760);
DISPLAY 0.489362 (-3360 4760);
WIRE 16 -1 (-3625 4700)(-2525 4700);
FORCEPROP 2 LAST SIG_NAME WAFL_CPU0_TX0_CPU1_RX1_DN
J 0
(-3360 4710);
DISPLAY 0.489362 (-3360 4710);
FORCEPROP 0 LAST $PHYS_NET_NAME P3E_M2_0_SATA_RX_DP
J 0
(-3435 4739);
DISPLAY INVISIBLE (-3435 4739);
WIRE 16 -1 (-3625 4400)(-2775 4400);
FORCEPROP 2 LAST SIG_NAME P2E_CPU0_P5_TX_DN
J 0
(-3425 4410);
DISPLAY 0.680851 (-3425 4410);
FORCEPROP 2 LASTPROP $XRERR UNIQUE?
J 0
(-3665 4410);
DISPLAY 0.638298 (-3665 4410);
PAINT MONO (-3665 4410);
DISPLAY INVISIBLE (-3665 4410);
WIRE 16 -1 (-6625 4400)(-5525 4400);
FORCEPROP 2 LAST SIG_NAME P2E_CPU0_P5_RX_DN
J 0
(-6510 4410);
DISPLAY 0.489362 (-6510 4410);
WIRE 16 -1 (-6625 4450)(-5525 4450);
FORCEPROP 2 LAST SIG_NAME P2E_CPU0_P5_RX_DP
J 0
(-6510 4460);
DISPLAY 0.489362 (-6510 4460);
WIRE 16 -1 (-3625 4450)(-2775 4450);
FORCEPROP 2 LAST SIG_NAME P2E_CPU0_P5_TX_DP
J 0
(-3425 4460);
DISPLAY 0.680851 (-3425 4460);
FORCEPROP 2 LASTPROP $XRERR UNIQUE?
J 0
(-3665 4460);
DISPLAY 0.638298 (-3665 4460);
PAINT MONO (-3665 4460);
DISPLAY INVISIBLE (-3665 4460);
WIRE 16 -1 (-6150 5150)(-5525 5150);
WIRE 16 -1 (-3625 5000)(-3250 5000);
WIRE 16 -1 (-3625 4950)(-3100 4950);
WIRE 16 -1 (-3625 4900)(-3250 4900);
WIRE 16 -1 (-6625 4700)(-5525 4700);
FORCEPROP 2 LAST SIG_NAME WAFL_CPU1_TX1_CPU0_RX0_DN
J 0
(-6535 4710);
DISPLAY 0.489362 (-6535 4710);
FORCEPROP 0 LAST $PHYS_NET_NAME P3E_M2_0_SATA_RX_DP
J 0
(-6435 4739);
DISPLAY INVISIBLE (-6435 4739);
WIRE 16 -1 (-6625 4750)(-5525 4750);
FORCEPROP 2 LAST SIG_NAME WAFL_CPU1_TX1_CPU0_RX0_DP
J 0
(-6535 4760);
DISPLAY 0.489362 (-6535 4760);
WIRE 16 -1 (-6150 4950)(-5525 4950);
WIRE 16 -1 (-6150 4850)(-5525 4850);
WIRE 16 -1 (-6000 4900)(-5525 4900);
WIRE 16 -1 (-3625 5200)(-3250 5200);
WIRE 16 -1 (-3625 5100)(-3250 5100);
WIRE 16 -1 (-3625 5150)(-3100 5150);
WIRE 16 -1 (-6000 5200)(-5525 5200);
WIRE 16 -1 (-3625 5050)(-3100 5050);
WIRE 16 -1 (-6000 5100)(-5525 5100);
WIRE 16 -1 (-6150 5050)(-5525 5050);
WIRE 16 -1 (-6000 5000)(-5525 5000);
FORCENOTE
CPU0 P5[2] TO SCM CONN
(-3575 3875) 0;
DISPLAY LEFT (-3575 3875);
DISPLAY 2.000000 (-3575 3875);
FORCENOTE
CPU0 P4[3:0] TO E1.S
(-2450 5075) 0;
DISPLAY LEFT (-2450 5075);
DISPLAY 2.000000 (-2450 5075);
QUIT
